# S9S_MB_2U (Grand Teton) — schematic netlist excerpt (pin names and nets, part order shuffled) for the footprints in the layout excerpt that follows; sources: Cadence DE-HDL packaged netlist, KiCad conversion of 03242023_DA0F0TMBIJ0_F0T_Motherboard_J_brd_V01_OCP.brd

R1349  Q_RES  0 5% CHIP  pkg 0402LF  page 134 : A = JTAG_DBP_TCK_PCH_R ; B = JTAG_DBP_TCK_PCH
R1843  Q_RES  33.2 1% CHIP  pkg 0402LF  page 222 : A = RST_PFR_OVR_RTC_R ; B = RST_PFR_OVR_RTC

(kicad_pcb
	(version 20260206)
	(generator "pcbnew")
	(generator_version "10.0")
	(general
		(thickness 1.6)
		(legacy_teardrops no)
	)
	(paper "A4")
	(title_block
		(title "03242023_DA0F0TMBIJ0_F0T_Motherboard_J_brd_V01_OCP.brd")
		(comment 1 "Grand Teton / footprints 2825-2826 of 6105")
	)
	(layers
		(0 "F.Cu" signal "TOP")
		(4 "In1.Cu" signal "GND")
		(6 "In2.Cu" signal "IN1")
		(8 "In3.Cu" signal "GND1")
		(10 "In4.Cu" signal "IN2")
		(12 "In5.Cu" signal "GND2")
		(14 "In6.Cu" signal "IN3")
		(16 "In7.Cu" signal "GND3")
		(18 "In8.Cu" signal "VCC")
		(20 "In9.Cu" signal "VCC1")
		(22 "In10.Cu" signal "GND4")
		(24 "In11.Cu" signal "IN4")
		(26 "In12.Cu" signal "GND5")
		(28 "In13.Cu" signal "IN5")
		(30 "In14.Cu" signal "GND6")
		(32 "In15.Cu" signal "IN6")
		(34 "In16.Cu" signal "GND7")
		(2 "B.Cu" signal "BOTTOM")
		(9 "F.Adhes" user "F.Adhesive")
		(11 "B.Adhes" user "B.Adhesive")
		(13 "F.Paste" user "Package Geometry/Pastemask Top")
		(15 "B.Paste" user "Package Geometry/Pastemask Bottom")
		(5 "F.SilkS" user "Ref Des/Silkscreen Top")
		(7 "B.SilkS" user "Ref Des/Silkscreen Bottom")
		(1 "F.Mask" user "Board Geometry/Soldermask Top")
		(3 "B.Mask" user "Board Geometry/Soldermask Bottom")
		(17 "Dwgs.User" user "User.Drawings")
		(19 "Cmts.User" user "User.Comments")
		(21 "Eco1.User" user "User.Eco1")
		(23 "Eco2.User" user "User.Eco2")
		(25 "Edge.Cuts" user "Board Geometry/Outline")
		(27 "Margin" user)
		(31 "F.CrtYd" user "Package Geometry/Place Bound Top")
		(29 "B.CrtYd" user "Package Geometry/Place Bound Bottom")
		(35 "F.Fab" user "Ref Des/Assembly Top")
		(33 "B.Fab" user "Ref Des/Assembly Bottom")
	)
	(footprint ""
		(layer "F.Cu")
		(at 197.41388 -102.415848)
		(property "Reference" "R1843"
			(at 0 0 0)
			(layer "F.SilkS")
			(hide yes)
			(effects
				(font
					(size 1.27 1.27)
				)
			)
		)
		(property "Value" ""
			(at 0 0 0)
			(layer "F.Fab")
			(effects
				(font
					(size 1.27 1.27)
				)
			)
		)
		(duplicate_pad_numbers_are_jumpers no)
		(fp_line
			(start -0.7874 -0.4064)
			(end 0.7874 -0.4064)
			(stroke
				(width 0.1524)
				(type default)
			)
			(layer "F.SilkS")
		)
		(fp_line
			(start -0.7874 0.4064)
			(end -0.7874 -0.4064)
			(stroke
				(width 0.1524)
				(type default)
			)
			(layer "F.SilkS")
		)
		(fp_line
			(start 0.7874 -0.4064)
			(end 0.7874 0.4064)
			(stroke
				(width 0.1524)
				(type default)
			)
			(layer "F.SilkS")
		)
		(fp_line
			(start 0.7874 0.4064)
			(end -0.7874 0.4064)
			(stroke
				(width 0.1524)
				(type default)
			)
			(layer "F.SilkS")
		)
		(fp_line
			(start -0.67945 -0.305054)
			(end -0.12065 -0.305054)
			(stroke
				(width 0.1)
				(type default)
			)
			(layer "F.Fab")
		)
		(fp_line
			(start -0.67945 0.3048)
			(end -0.67945 -0.305054)
			(stroke
				(width 0.1)
				(type default)
			)
			(layer "F.Fab")
		)
		(fp_line
			(start -0.12065 -0.305054)
			(end -0.12065 -0.2794)
			(stroke
				(width 0.1)
				(type default)
			)
			(layer "F.Fab")
		)
		(fp_line
			(start -0.12065 -0.2794)
			(end 0.12065 -0.2794)
			(stroke
				(width 0.1)
				(type default)
			)
			(layer "F.Fab")
		)
		(fp_line
			(start -0.12065 0.2794)
			(end -0.12065 0.3048)
			(stroke
				(width 0.1)
				(type default)
			)
			(layer "F.Fab")
		)
		(fp_line
			(start -0.12065 0.3048)
			(end -0.67945 0.3048)
			(stroke
				(width 0.1)
				(type default)
			)
			(layer "F.Fab")
		)
		(fp_line
			(start 0.120396 0.2794)
			(end -0.12065 0.2794)
			(stroke
				(width 0.1)
				(type default)
			)
			(layer "F.Fab")
		)
		(fp_line
			(start 0.120396 0.3048)
			(end 0.120396 0.2794)
			(stroke
				(width 0.1)
				(type default)
			)
			(layer "F.Fab")
		)
		(fp_line
			(start 0.12065 -0.3048)
			(end 0.67945 -0.3048)
			(stroke
				(width 0.1)
				(type default)
			)
			(layer "F.Fab")
		)
		(fp_line
			(start 0.12065 -0.2794)
			(end 0.12065 -0.3048)
			(stroke
				(width 0.1)
				(type default)
			)
			(layer "F.Fab")
		)
		(fp_line
			(start 0.67945 -0.3048)
			(end 0.67945 0.3048)
			(stroke
				(width 0.1)
				(type default)
			)
			(layer "F.Fab")
		)
		(fp_line
			(start 0.67945 0.3048)
			(end 0.120396 0.3048)
			(stroke
				(width 0.1)
				(type default)
			)
			(layer "F.Fab")
		)
		(pad "1" smd circle
			(at -0.40005 0)
			(size 0 0)
			(layers "F.Cu" "F.Mask" "F.Paste")
			(net "RST_PFR_OVR_RTC_R")
		)
		(pad "2" smd circle
			(at 0.40005 0)
			(size 0 0)
			(layers "F.Cu" "F.Mask" "F.Paste")
			(net "RST_PFR_OVR_RTC")
		)
	)
	(footprint ""
		(layer "F.Cu")
		(at 109.14888 -53.304948)
		(property "Reference" "R1349"
			(at 0 0 0)
			(layer "F.SilkS")
			(hide yes)
			(effects
				(font
					(size 1.27 1.27)
				)
			)
		)
		(property "Value" ""
			(at 0 0 0)
			(layer "F.Fab")
			(effects
				(font
					(size 1.27 1.27)
				)
			)
		)
		(duplicate_pad_numbers_are_jumpers no)
		(fp_line
			(start -0.7874 -0.4064)
			(end 0.7874 -0.4064)
			(stroke
				(width 0.1524)
				(type default)
			)
			(layer "F.SilkS")
		)
		(fp_line
			(start -0.7874 0.4064)
			(end -0.7874 -0.4064)
			(stroke
				(width 0.1524)
				(type default)
			)
			(layer "F.SilkS")
		)
		(fp_line
			(start 0.7874 -0.4064)
			(end 0.7874 0.4064)
			(stroke
				(width 0.1524)
				(type default)
			)
			(layer "F.SilkS")
		)
		(fp_line
			(start 0.7874 0.4064)
			(end -0.7874 0.4064)
			(stroke
				(width 0.1524)
				(type default)
			)
			(layer "F.SilkS")
		)
		(fp_line
			(start -0.67945 -0.305054)
			(end -0.12065 -0.305054)
			(stroke
				(width 0.1)
				(type default)
			)
			(layer "F.Fab")
		)
		(fp_line
			(start -0.67945 0.3048)
			(end -0.67945 -0.305054)
			(stroke
				(width 0.1)
				(type default)
			)
			(layer "F.Fab")
		)
		(fp_line
			(start -0.12065 -0.305054)
			(end -0.12065 -0.2794)
			(stroke
				(width 0.1)
				(type default)
			)
			(layer "F.Fab")
		)
		(fp_line
			(start -0.12065 -0.2794)
			(end 0.12065 -0.2794)
			(stroke
				(width 0.1)
				(type default)
			)
			(layer "F.Fab")
		)
		(fp_line
			(start -0.12065 0.2794)
			(end -0.12065 0.3048)
			(stroke
				(width 0.1)
				(type default)
			)
			(layer "F.Fab")
		)
		(fp_line
			(start -0.12065 0.3048)
			(end -0.67945 0.3048)
			(stroke
				(width 0.1)
				(type default)
			)
			(layer "F.Fab")
		)
		(fp_line
			(start 0.120396 0.2794)
			(end -0.12065 0.2794)
			(stroke
				(width 0.1)
				(type default)
			)
			(layer "F.Fab")
		)
		(fp_line
			(start 0.120396 0.3048)
			(end 0.120396 0.2794)
			(stroke
				(width 0.1)
				(type default)
			)
			(layer "F.Fab")
		)
		(fp_line
			(start 0.12065 -0.3048)
			(end 0.67945 -0.3048)
			(stroke
				(width 0.1)
				(type default)
			)
			(layer "F.Fab")
		)
		(fp_line
			(start 0.12065 -0.2794)
			(end 0.12065 -0.3048)
			(stroke
				(width 0.1)
				(type default)
			)
			(layer "F.Fab")
		)
		(fp_line
			(start 0.67945 -0.3048)
			(end 0.67945 0.3048)
			(stroke
				(width 0.1)
				(type default)
			)
			(layer "F.Fab")
		)
		(fp_line
			(start 0.67945 0.3048)
			(end 0.120396 0.3048)
			(stroke
				(width 0.1)
				(type default)
			)
			(layer "F.Fab")
		)
		(pad "1" smd circle
			(at -0.40005 0)
			(size 0 0)
			(layers "F.Cu" "F.Mask" "F.Paste")
			(net "JTAG_DBP_TCK_PCH_R")
		)
		(pad "2" smd circle
			(at 0.40005 0)
			(size 0 0)
			(layers "F.Cu" "F.Mask" "F.Paste")
			(net "JTAG_DBP_TCK_PCH")
		)
	)
)
